# S9S_MB_2U (Grand Teton) — schematic netlist excerpt (pin names and nets, part order shuffled) for the footprints in the layout excerpt that follows; sources: Cadence DE-HDL packaged netlist, KiCad conversion of 03242023_DA0F0TMBIJ0_F0T_Motherboard_J_brd_V01_OCP.brd

J23  SCONN288_ADR50017P130CC  SCONN288_ADR50017-P130CC IO  pkg DDR288S_1-1VXB  page 104
  VIN_BULK0  = P12V_S3_AUX_CPU1_NVDIMM
  RFU0  = TP_CHD_CPU1_DIMM1_FRU_0
  VIN_MGMT  = P3V3_AUX
  HSCL  = I3C_SPD_DDRABCD_CPU1_LVC1_SCL_6
  HSDA  = I3C_SPD_DDRABCD_CPU1_LVC1_SDA
  VSS0  = GND
  DQ0_A  = M_D_CPU1_SA_DQ<0>
  VSS1  = GND
  DQ1_A  = M_D_CPU1_SA_DQ<1>
  VSS2  = GND
  DQS0_A_T  = M_D_CPU1_SA_DQS_DP<0>
  DQS0_A_C  = M_D_CPU1_SA_DQS_DN<0>
  VSS3  = GND
  DQ4_A  = M_D_CPU1_SA_DQ<4>
  VSS4  = GND
  DQ5_A  = M_D_CPU1_SA_DQ<5>
  VSS5  = GND
  DQ8_A  = M_D_CPU1_SA_DQ<8>
  VSS6  = GND
  DQ9_A  = M_D_CPU1_SA_DQ<9>
  VSS7  = GND
  DQS1_A_T  = M_D_CPU1_SA_DQS_DP<1>
  DQS1_A_C  = M_D_CPU1_SA_DQS_DN<1>
  VSS8  = GND
  DQ12_A  = M_D_CPU1_SA_DQ<12>
  VSS9  = GND
  DQ13_A  = M_D_CPU1_SA_DQ<13>
  VSS10  = GND
  DQ16_A  = M_D_CPU1_SA_DQ<16>
  VSS11  = GND
  DQ17_A  = M_D_CPU1_SA_DQ<17>
  VSS12  = GND
  DQS2_A_T  = M_D_CPU1_SA_DQS_DP<2>
  DQS2_A_C  = M_D_CPU1_SA_DQS_DN<2>
  VSS13  = GND
  DQ20_A  = M_D_CPU1_SA_DQ<20>
  VSS14  = GND
  DQ21_A  = M_D_CPU1_SA_DQ<21>
  VSS15  = GND
  DQ24_A  = M_D_CPU1_SA_DQ<24>
  VSS16  = GND
  DQ25_A  = M_D_CPU1_SA_DQ<25>
  VSS17  = GND
  DQS3_A_T  = M_D_CPU1_SA_DQS_DP<3>
  DQS3_A_C  = M_D_CPU1_SA_DQS_DN<3>
  VSS18  = GND
  DQ28_A  = M_D_CPU1_SA_DQ<28>
  VSS19  = GND
  DQ29_A  = M_D_CPU1_SA_DQ<29>
  VSS20  = GND
  CB0_A  = M_D_CPU1_SA_CB<0>
  VSS21  = GND
  CB1_A  = M_D_CPU1_SA_CB<1>
  VSS22  = GND
  DQS4_A_T  = M_D_CPU1_SA_DQS_DP<4>
  DQS4_A_C  = M_D_CPU1_SA_DQS_DN<4>
  VSS23  = GND
  CB4_A  = M_D_CPU1_SA_CB<4>
  VSS24  = GND
  CB5_A  = M_D_CPU1_SA_CB<5>
  VSS25  = GND
  ALERT_N  = M_D_CPU1_ALERT_N
  VSS26  = GND
  CS0_A_N  = M_D_CPU1_SA_CS_N<0>
  VSS27  = GND
  CA0_A  = M_D_CPU1_SA_CA<0>
  VSS28  = GND
  CA2_A  = M_D_CPU1_SA_CA<2>
  VSS29  = GND
  CA4_A  = M_D_CPU1_SA_CA<4>
  VSS30  = GND
  CA6_A  = M_D_CPU1_SA_CA<6>
  VSS31  = GND
  PAR_A  = M_D_CPU1_SA_PAR
  VSS32  = GND
  CA0_B  = M_D_CPU1_SB_CA<0>
  VSS33  = GND
  CA2_B  = M_D_CPU1_SB_CA<2>
  VSS34  = GND
  CA4_B  = M_D_CPU1_SB_CA<4>
  VSS35  = GND
  CA6_B  = M_D_CPU1_SB_CA<6>
  VSS36  = GND
  CS0_B_N  = M_D_CPU1_SB_CS_N<0>
  VSS37  = GND
  \lbd||rsp_a_n\  = M_D_CPU1_SA_RSP<0>
  \lbs||rsp_b_n\  = M_D_CPU1_SB_RSP<0>
  VSS38  = GND
  CB4_B  = M_D_CPU1_SB_CB<4>
  VSS39  = GND
  CB5_B  = M_D_CPU1_SB_CB<5>
  VSS40  = GND
  \dqs9_b_t||tdqs9_b_t||dbi4_b_n\  = M_D_CPU1_SB_DQS_DP<9>
  \dqs9_b_c||tdqs9_b_c\  = M_D_CPU1_SB_DQS_DN<9>
  VSS41  = GND
  CB0_B  = M_D_CPU1_SB_CB<0>
  VSS42  = GND
  CB1_B  = M_D_CPU1_SB_CB<1>
  VSS43  = GND
  DQ0_B  = M_D_CPU1_SB_DQ<0>
  VSS44  = GND
  DQ1_B  = M_D_CPU1_SB_DQ<1>
  VSS45  = GND
  DQS0_B_T  = M_D_CPU1_SB_DQS_DP<0>
  DQS0_B_C  = M_D_CPU1_SB_DQS_DN<0>
  VSS46  = GND
  DQ4_B  = M_D_CPU1_SB_DQ<4>
  VSS47  = GND
  DQ5_B  = M_D_CPU1_SB_DQ<5>
  VSS48  = GND
  DQ8_B  = M_D_CPU1_SB_DQ<8>
  VSS49  = GND
  DQ9_B  = M_D_CPU1_SB_DQ<9>
  VSS50  = GND
  DQS1_B_T  = M_D_CPU1_SB_DQS_DP<1>
  DQS1_B_C  = M_D_CPU1_SB_DQS_DN<1>
  VSS51  = GND
  DQ12_B  = M_D_CPU1_SB_DQ<12>
  VSS52  = GND
  DQ13_B  = M_D_CPU1_SB_DQ<13>
  VSS53  = GND
  DQ16_B  = M_D_CPU1_SB_DQ<16>
  VSS54  = GND
  DQ17_B  = M_D_CPU1_SB_DQ<17>
  VSS55  = GND
  DQS2_B_T  = M_D_CPU1_SB_DQS_DP<2>
  DQS2_B_C  = M_D_CPU1_SB_DQS_DN<2>
  VSS56  = GND
  DQ20_B  = M_D_CPU1_SB_DQ<20>
  VSS57  = GND
  DQ21_B  = M_D_CPU1_SB_DQ<21>
  VSS58  = GND
  DQ24_B  = M_D_CPU1_SB_DQ<24>
  VSS59  = GND
  DQ25_B  = M_D_CPU1_SB_DQ<25>
  VSS60  = GND
  DQS3_B_T  = M_D_CPU1_SB_DQS_DP<3>
  DQS3_B_C  = M_D_CPU1_SB_DQS_DN<3>
  VSS61  = GND
  DQ28_B  = M_D_CPU1_SB_DQ<28>
  VSS62  = GND
  DQ29_B  = M_D_CPU1_SB_DQ<29>
  VSS63  = GND
  RFU1  = TP_CHD_CPU1_DIMM1_FRU_1
  VIN_BULK1  = P12V_S3_AUX_CPU1_NVDIMM
  VIN_BULK2  = P12V_S3_AUX_CPU1_NVDIMM
  \pwr_good||fail_n\  = PWRGD_CHD_CPU1_DIMM1
  HSA  = PD_CHD_CPU1_DIMM1_SAA
  RFU2  = TP_CHD_CPU1_DIMM1_FRU_2
  RFU3  = TP_CHD_CPU1_DIMM1_FRU_3
  VSS64  = GND
  DQ2_A  = M_D_CPU1_SA_DQ<2>
  VSS65  = GND
  DQ3_A  = M_D_CPU1_SA_DQ<3>
  VSS66  = GND
  \dqs5_a_c||tdqs5_a_c||dqs5_a_t||tdqs5_a_t\  = M_D_CPU1_SA_DQS_DN<5>
  \dqs5_a_t||tdqs5_a_t\  = M_D_CPU1_SA_DQS_DP<5>
  VSS67  = GND
  DQ6_A  = M_D_CPU1_SA_DQ<6>
  VSS68  = GND
  DQ7_A  = M_D_CPU1_SA_DQ<7>
  VSS69  = GND
  DQ10_A  = M_D_CPU1_SA_DQ<10>
  VSS70  = GND
  DQ11_A  = M_D_CPU1_SA_DQ<11>
  VSS71  = GND
  \dqs6_a_c||tdqs6_a_c||dqs6_a_t||tdqs6_a_t\  = M_D_CPU1_SA_DQS_DN<6>
  \dqs6_a_t||tdqs6_a_t\  = M_D_CPU1_SA_DQS_DP<6>
  VSS72  = GND
  DQ14_A  = M_D_CPU1_SA_DQ<14>
  VSS73  = GND
  DQ15_A  = M_D_CPU1_SA_DQ<15>
  VSS74  = GND
  DQ18_A  = M_D_CPU1_SA_DQ<18>
  VSS75  = GND
  DQ19_A  = M_D_CPU1_SA_DQ<19>
  VSS76  = GND
  \dqs7_a_c||tdqs7_a_c\  = M_D_CPU1_SA_DQS_DN<7>
  \dqs7_a_t||tdqs7_a_t\  = M_D_CPU1_SA_DQS_DP<7>
  VSS77  = GND
  DQ22_A  = M_D_CPU1_SA_DQ<22>
  VSS78  = GND
  DQ23_A  = M_D_CPU1_SA_DQ<23>
  VSS79  = GND
  DQ26_A  = M_D_CPU1_SA_DQ<26>
  VSS80  = GND
  DQ27_A  = M_D_CPU1_SA_DQ<27>
  VSS81  = GND
  \dqs8_a_c||tdqs8_a_c\  = M_D_CPU1_SA_DQS_DN<8>
  \dqs8_a_t||tdqs8_a_t\  = M_D_CPU1_SA_DQS_DP<8>
  VSS82  = GND
  DQ30_A  = M_D_CPU1_SA_DQ<30>
  VSS83  = GND
  DQ31_A  = M_D_CPU1_SA_DQ<31>
  VSS84  = GND
  CB2_A  = M_D_CPU1_SA_CB<2>
  VSS85  = GND
  CB3_A  = M_D_CPU1_SA_CB<3>
  VSS86  = GND
  \dqs9_a_c||tdqs9_a_c\  = M_D_CPU1_SA_DQS_DN<9>
  \dqs9_a_t||tdqs9_a_t\  = M_D_CPU1_SA_DQS_DP<9>
  VSS87  = GND
  CB6_A  = M_D_CPU1_SA_CB<6>
  VSS88  = GND
  CB7_A  = M_D_CPU1_SA_CB<7>
  VSS89  = GND
  RESET_N  = RST_M_CD_CPU1_FPGA_N
  VSS90  = GND
  CS1_A_N  = M_D_CPU1_SA_CS_N<1>
  VSS91  = GND
  CA1_A  = M_D_CPU1_SA_CA<1>
  VSS92  = GND
  CA3_A  = M_D_CPU1_SA_CA<3>
  VSS93  = GND
  CA5_A  = M_D_CPU1_SA_CA<5>
  VSS94  = GND
  CK_T  = M_D_CPU1_CLK_DP<0>
  CK_C  = M_D_CPU1_CLK_DN<0>
  VSS95  = GND
  RFU4  = TP_CHD_CPU1_DIMM1_FRU_4
  CA1_B  = M_D_CPU1_SB_CA<1>
  VSS96  = GND
  CA3_B  = M_D_CPU1_SB_CA<3>
  VSS97  = GND
  CA5_B  = M_D_CPU1_SB_CA<5>
  VSS98  = GND
  PAR_B  = M_D_CPU1_SB_PAR
  VSS99  = GND
  CS1_B_N  = M_D_CPU1_SB_CS_N<1>
  VSS100  = GND
  RFU5  = TP_CHD_CPU1_DIMM1_FRU_5
  RFU6  = TP_CHD_CPU1_DIMM1_FRU_6
  VSS101  = GND
  CB6_B  = M_D_CPU1_SB_CB<6>
  VSS102  = GND
  CB7_B  = M_D_CPU1_SB_CB<7>
  VSS103  = GND
  DQS4_B_C  = M_D_CPU1_SB_DQS_DN<4>
  DQS4_B_T  = M_D_CPU1_SB_DQS_DP<4>
  VSS104  = GND
  CB2_B  = M_D_CPU1_SB_CB<2>
  VSS105  = GND
  CB3_B  = M_D_CPU1_SB_CB<3>
  VSS106  = GND
  DQ2_B  = M_D_CPU1_SB_DQ<2>
  VSS107  = GND
  DQ3_B  = M_D_CPU1_SB_DQ<3>
  VSS108  = GND
  \dqs5_b_c||tdqs5_b_c\  = M_D_CPU1_SB_DQS_DN<5>
  \dqs5_b_t||tdqs5_b_t\  = M_D_CPU1_SB_DQS_DP<5>
  VSS109  = GND
  DQ6_B  = M_D_CPU1_SB_DQ<6>
  VSS110  = GND
  DQ7_B  = M_D_CPU1_SB_DQ<7>
  VSS111  = GND
  DQ10_B  = M_D_CPU1_SB_DQ<10>
  VSS112  = GND
  DQ11_B  = M_D_CPU1_SB_DQ<11>
  VSS113  = GND
  \dqs6_b_c||tdqs6_b_c\  = M_D_CPU1_SB_DQS_DN<6>
  \dqs6_b_t||tdqs6_b_t\  = M_D_CPU1_SB_DQS_DP<6>
  VSS114  = GND
  DQ14_B  = M_D_CPU1_SB_DQ<14>
  VSS115  = GND
  DQ15_B  = M_D_CPU1_SB_DQ<15>
  VSS116  = GND
  DQ18_B  = M_D_CPU1_SB_DQ<18>
  VSS117  = GND
  DQ19_B  = M_D_CPU1_SB_DQ<19>
  VSS118  = GND
  \dqs7_b_c||tdqs7_b_c\  = M_D_CPU1_SB_DQS_DN<7>
  \dqs7_b_t||tdqs7_b_t\  = M_D_CPU1_SB_DQS_DP<7>
  VSS119  = GND
  DQ22_B  = M_D_CPU1_SB_DQ<22>
  VSS120  = GND
  DQ23_B  = M_D_CPU1_SB_DQ<23>
  VSS121  = GND
  DQ26_B  = M_D_CPU1_SB_DQ<26>
  VSS122  = GND
  DQ27_B  = M_D_CPU1_SB_DQ<27>
  VSS123  = GND
  \dqs8_b_c||tdqs8_b_c\  = M_D_CPU1_SB_DQS_DN<8>
  \dqs8_b_t||tdqs8_b_t\  = M_D_CPU1_SB_DQS_DP<8>
  VSS124  = GND
  DQ30_B  = M_D_CPU1_SB_DQ<30>
  VSS125  = GND
  DQ31_B  = M_D_CPU1_SB_DQ<31>
  VSS126  = GND
  G1  = GND
  G2  = GND
  G3  = GND

(kicad_pcb
	(version 20260206)
	(generator "pcbnew")
	(generator_version "10.0")
	(general
		(thickness 1.6)
		(legacy_teardrops no)
	)
	(paper "A4")
	(title_block
		(title "03242023_DA0F0TMBIJ0_F0T_Motherboard_J_brd_V01_OCP.brd")
		(comment 1 "Grand Teton / footprint 3586 of 6105 (J23), pads 92-137 of 291")
	)
	(layers
		(0 "F.Cu" signal "TOP")
		(4 "In1.Cu" signal "GND")
		(6 "In2.Cu" signal "IN1")
		(8 "In3.Cu" signal "GND1")
		(10 "In4.Cu" signal "IN2")
		(12 "In5.Cu" signal "GND2")
		(14 "In6.Cu" signal "IN3")
		(16 "In7.Cu" signal "GND3")
		(18 "In8.Cu" signal "VCC")
		(20 "In9.Cu" signal "VCC1")
		(22 "In10.Cu" signal "GND4")
		(24 "In11.Cu" signal "IN4")
		(26 "In12.Cu" signal "GND5")
		(28 "In13.Cu" signal "IN5")
		(30 "In14.Cu" signal "GND6")
		(32 "In15.Cu" signal "IN6")
		(34 "In16.Cu" signal "GND7")
		(2 "B.Cu" signal "BOTTOM")
		(9 "F.Adhes" user "F.Adhesive")
		(11 "B.Adhes" user "B.Adhesive")
		(13 "F.Paste" user "Package Geometry/Pastemask Top")
		(15 "B.Paste" user "Package Geometry/Pastemask Bottom")
		(5 "F.SilkS" user "Ref Des/Silkscreen Top")
		(7 "B.SilkS" user "Ref Des/Silkscreen Bottom")
		(1 "F.Mask" user "Board Geometry/Soldermask Top")
		(3 "B.Mask" user "Board Geometry/Soldermask Bottom")
		(17 "Dwgs.User" user "User.Drawings")
		(19 "Cmts.User" user "User.Comments")
		(21 "Eco1.User" user "User.Eco1")
		(23 "Eco2.User" user "User.Eco2")
		(25 "Edge.Cuts" user "Board Geometry/Outline")
		(27 "Margin" user)
		(31 "F.CrtYd" user "Package Geometry/Place Bound Top")
		(29 "B.CrtYd" user "Package Geometry/Place Bound Bottom")
		(35 "F.Fab" user "Ref Des/Assembly Top")
		(33 "B.Fab" user "Ref Des/Assembly Bottom")
	)
	(footprint ""
		(layer "F.Cu")
		(at 10.19048 -258.091686)
		(property "Reference" "J23"
			(at -5.69468 -80.480408 0)
			(unlocked yes)
			(layer "F.SilkS")
			(effects
				(font
					(size 0.7874 0.5842)
					(thickness 0.1524)
				)
				(justify left)
			)
		)
		(property "Value" ""
			(at 0 0 0)
			(layer "F.Fab")
			(effects
				(font
					(size 1.27 1.27)
				)
			)
		)
		(duplicate_pad_numbers_are_jumpers no)
		(pad "92" smd rect
			(at -2.050034 19.12493 270)
			(size 0.519938 1.4986)
			(layers "F.Cu" "F.Mask" "F.Paste")
			(net "GND")
		)
		(pad "93" smd rect
			(at -2.050034 19.975068 270)
			(size 0.519938 1.4986)
			(layers "F.Cu" "F.Mask" "F.Paste")
			(net "M_D_CPU1_SB_DQS_DP<9>")
		)
		(pad "94" smd rect
			(at -2.050034 20.824952 270)
			(size 0.519938 1.4986)
			(layers "F.Cu" "F.Mask" "F.Paste")
			(net "M_D_CPU1_SB_DQS_DN<9>")
		)
		(pad "95" smd rect
			(at -2.050034 21.67509 270)
			(size 0.519938 1.4986)
			(layers "F.Cu" "F.Mask" "F.Paste")
			(net "GND")
		)
		(pad "96" smd rect
			(at -2.050034 22.524974 270)
			(size 0.519938 1.4986)
			(layers "F.Cu" "F.Mask" "F.Paste")
			(net "M_D_CPU1_SB_CB<0>")
		)
		(pad "97" smd rect
			(at -2.050034 23.375112 270)
			(size 0.519938 1.4986)
			(layers "F.Cu" "F.Mask" "F.Paste")
			(net "GND")
		)
		(pad "98" smd rect
			(at -2.050034 24.224996 270)
			(size 0.519938 1.4986)
			(layers "F.Cu" "F.Mask" "F.Paste")
			(net "M_D_CPU1_SB_CB<1>")
		)
		(pad "99" smd rect
			(at -2.050034 25.07488 270)
			(size 0.519938 1.4986)
			(layers "F.Cu" "F.Mask" "F.Paste")
			(net "GND")
		)
		(pad "100" smd rect
			(at -2.050034 25.925018 270)
			(size 0.519938 1.4986)
			(layers "F.Cu" "F.Mask" "F.Paste")
			(net "M_D_CPU1_SB_DQ<0>")
		)
		(pad "101" smd rect
			(at -2.050034 26.774902 270)
			(size 0.519938 1.4986)
			(layers "F.Cu" "F.Mask" "F.Paste")
			(net "GND")
		)
		(pad "102" smd rect
			(at -2.050034 27.62504 270)
			(size 0.519938 1.4986)
			(layers "F.Cu" "F.Mask" "F.Paste")
			(net "M_D_CPU1_SB_DQ<1>")
		)
		(pad "103" smd rect
			(at -2.050034 28.474924 270)
			(size 0.519938 1.4986)
			(layers "F.Cu" "F.Mask" "F.Paste")
			(net "GND")
		)
		(pad "104" smd rect
			(at -2.050034 29.325062 270)
			(size 0.519938 1.4986)
			(layers "F.Cu" "F.Mask" "F.Paste")
			(net "M_D_CPU1_SB_DQS_DP<0>")
		)
		(pad "105" smd rect
			(at -2.050034 30.174946 270)
			(size 0.519938 1.4986)
			(layers "F.Cu" "F.Mask" "F.Paste")
			(net "M_D_CPU1_SB_DQS_DN<0>")
		)
		(pad "106" smd rect
			(at -2.050034 31.025084 270)
			(size 0.519938 1.4986)
			(layers "F.Cu" "F.Mask" "F.Paste")
			(net "GND")
		)
		(pad "107" smd rect
			(at -2.050034 31.874968 270)
			(size 0.519938 1.4986)
			(layers "F.Cu" "F.Mask" "F.Paste")
			(net "M_D_CPU1_SB_DQ<4>")
		)
		(pad "108" smd rect
			(at -2.050034 32.725106 270)
			(size 0.519938 1.4986)
			(layers "F.Cu" "F.Mask" "F.Paste")
			(net "GND")
		)
		(pad "109" smd rect
			(at -2.050034 33.57499 270)
			(size 0.519938 1.4986)
			(layers "F.Cu" "F.Mask" "F.Paste")
			(net "M_D_CPU1_SB_DQ<5>")
		)
		(pad "110" smd rect
			(at -2.050034 34.425128 270)
			(size 0.519938 1.4986)
			(layers "F.Cu" "F.Mask" "F.Paste")
			(net "GND")
		)
		(pad "111" smd rect
			(at -2.050034 35.275012 270)
			(size 0.519938 1.4986)
			(layers "F.Cu" "F.Mask" "F.Paste")
			(net "M_D_CPU1_SB_DQ<8>")
		)
		(pad "112" smd rect
			(at -2.050034 36.124896 270)
			(size 0.519938 1.4986)
			(layers "F.Cu" "F.Mask" "F.Paste")
			(net "GND")
		)
		(pad "113" smd rect
			(at -2.050034 36.975034 270)
			(size 0.519938 1.4986)
			(layers "F.Cu" "F.Mask" "F.Paste")
			(net "M_D_CPU1_SB_DQ<9>")
		)
		(pad "114" smd rect
			(at -2.050034 37.824918 270)
			(size 0.519938 1.4986)
			(layers "F.Cu" "F.Mask" "F.Paste")
			(net "GND")
		)
		(pad "115" smd rect
			(at -2.050034 38.675056 270)
			(size 0.519938 1.4986)
			(layers "F.Cu" "F.Mask" "F.Paste")
			(net "M_D_CPU1_SB_DQS_DP<1>")
		)
		(pad "116" smd rect
			(at -2.050034 39.52494 270)
			(size 0.519938 1.4986)
			(layers "F.Cu" "F.Mask" "F.Paste")
			(net "M_D_CPU1_SB_DQS_DN<1>")
		)
		(pad "117" smd rect
			(at -2.050034 40.375078 270)
			(size 0.519938 1.4986)
			(layers "F.Cu" "F.Mask" "F.Paste")
			(net "GND")
		)
		(pad "118" smd rect
			(at -2.050034 41.224962 270)
			(size 0.519938 1.4986)
			(layers "F.Cu" "F.Mask" "F.Paste")
			(net "M_D_CPU1_SB_DQ<12>")
		)
		(pad "119" smd rect
			(at -2.050034 42.0751 270)
			(size 0.519938 1.4986)
			(layers "F.Cu" "F.Mask" "F.Paste")
			(net "GND")
		)
		(pad "120" smd rect
			(at -2.050034 42.924984 270)
			(size 0.519938 1.4986)
			(layers "F.Cu" "F.Mask" "F.Paste")
			(net "M_D_CPU1_SB_DQ<13>")
		)
		(pad "121" smd rect
			(at -2.050034 43.775122 270)
			(size 0.519938 1.4986)
			(layers "F.Cu" "F.Mask" "F.Paste")
			(net "GND")
		)
		(pad "122" smd rect
			(at -2.050034 44.625006 270)
			(size 0.519938 1.4986)
			(layers "F.Cu" "F.Mask" "F.Paste")
			(net "M_D_CPU1_SB_DQ<16>")
		)
		(pad "123" smd rect
			(at -2.050034 45.47489 270)
			(size 0.519938 1.4986)
			(layers "F.Cu" "F.Mask" "F.Paste")
			(net "GND")
		)
		(pad "124" smd rect
			(at -2.050034 46.325028 270)
			(size 0.519938 1.4986)
			(layers "F.Cu" "F.Mask" "F.Paste")
			(net "M_D_CPU1_SB_DQ<17>")
		)
		(pad "125" smd rect
			(at -2.050034 47.174912 270)
			(size 0.519938 1.4986)
			(layers "F.Cu" "F.Mask" "F.Paste")
			(net "GND")
		)
		(pad "126" smd rect
			(at -2.050034 48.02505 270)
			(size 0.519938 1.4986)
			(layers "F.Cu" "F.Mask" "F.Paste")
			(net "M_D_CPU1_SB_DQS_DP<2>")
		)
		(pad "127" smd rect
			(at -2.050034 48.874934 270)
			(size 0.519938 1.4986)
			(layers "F.Cu" "F.Mask" "F.Paste")
			(net "M_D_CPU1_SB_DQS_DN<2>")
		)
		(pad "128" smd rect
			(at -2.050034 49.725072 270)
			(size 0.519938 1.4986)
			(layers "F.Cu" "F.Mask" "F.Paste")
			(net "GND")
		)
		(pad "129" smd rect
			(at -2.050034 50.574956 270)
			(size 0.519938 1.4986)
			(layers "F.Cu" "F.Mask" "F.Paste")
			(net "M_D_CPU1_SB_DQ<20>")
		)
		(pad "130" smd rect
			(at -2.050034 51.425094 270)
			(size 0.519938 1.4986)
			(layers "F.Cu" "F.Mask" "F.Paste")
			(net "GND")
		)
		(pad "131" smd rect
			(at -2.050034 52.274978 270)
			(size 0.519938 1.4986)
			(layers "F.Cu" "F.Mask" "F.Paste")
			(net "M_D_CPU1_SB_DQ<21>")
		)
		(pad "132" smd rect
			(at -2.050034 53.125116 270)
			(size 0.519938 1.4986)
			(layers "F.Cu" "F.Mask" "F.Paste")
			(net "GND")
		)
		(pad "133" smd rect
			(at -2.050034 53.975 270)
			(size 0.519938 1.4986)
			(layers "F.Cu" "F.Mask" "F.Paste")
			(net "M_D_CPU1_SB_DQ<24>")
		)
		(pad "134" smd rect
			(at -2.050034 54.824884 270)
			(size 0.519938 1.4986)
			(layers "F.Cu" "F.Mask" "F.Paste")
			(net "GND")
		)
		(pad "135" smd rect
			(at -2.050034 55.675022 270)
			(size 0.519938 1.4986)
			(layers "F.Cu" "F.Mask" "F.Paste")
			(net "M_D_CPU1_SB_DQ<25>")
		)
		(pad "136" smd rect
			(at -2.050034 56.524906 270)
			(size 0.519938 1.4986)
			(layers "F.Cu" "F.Mask" "F.Paste")
			(net "GND")
		)
		(pad "137" smd rect
			(at -2.050034 57.375044 270)
			(size 0.519938 1.4986)
			(layers "F.Cu" "F.Mask" "F.Paste")
			(net "M_D_CPU1_SB_DQS_DP<3>")
		)
	)
)
